# T6G (Grand Teton) — schematic netlist excerpt (pin names and nets, part order shuffled) for the footprints in the layout excerpt that follows; sources: Cadence DE-HDL packaged netlist, KiCad conversion of 04192023_DAF0TMB3IC0_F0TG_MB_C_brd_V02_OCP.brd

C310  Q_CAP  10PF 50V 5% EMPTY  pkg 0402  page 217 : A = SVID_PVDDCR_CPU1_P1_SVC_R ; B = GND
PC201  Q_CAP  560PF 50V 10% EMPTY  pkg C0402  page 218 : A = SW_PVDDCR_CPU1_P1_SW1 ; B = SW_PVDDCR_CPU1_P1_SW1_RC

(kicad_pcb
	(version 20260206)
	(generator "pcbnew")
	(generator_version "10.0")
	(general
		(thickness 1.6)
		(legacy_teardrops no)
	)
	(paper "A4")
	(title_block
		(title "04192023_DAF0TMB3IC0_F0TG_MB_C_brd_V02_OCP.brd")
		(comment 1 "Grand Teton / footprints 431-432 of 8354")
	)
	(layers
		(0 "F.Cu" signal "TOP")
		(4 "In1.Cu" signal "GND")
		(6 "In2.Cu" signal "IN1")
		(8 "In3.Cu" signal "GND1")
		(10 "In4.Cu" signal "IN2")
		(12 "In5.Cu" signal "GND2")
		(14 "In6.Cu" signal "IN3")
		(16 "In7.Cu" signal "GND3")
		(18 "In8.Cu" signal "VCC")
		(20 "In9.Cu" signal "VCC1")
		(22 "In10.Cu" signal "GND4")
		(24 "In11.Cu" signal "IN4")
		(26 "In12.Cu" signal "GND5")
		(28 "In13.Cu" signal "IN5")
		(30 "In14.Cu" signal "GND6")
		(32 "In15.Cu" signal "IN6")
		(34 "In16.Cu" signal "GND7")
		(2 "B.Cu" signal "BOTTOM")
		(9 "F.Adhes" user "F.Adhesive")
		(11 "B.Adhes" user "B.Adhesive")
		(13 "F.Paste" user "Package Geometry/Pastemask Top")
		(15 "B.Paste" user "Package Geometry/Pastemask Bottom")
		(5 "F.SilkS" user "Ref Des/Silkscreen Top")
		(7 "B.SilkS" user "Ref Des/Silkscreen Bottom")
		(1 "F.Mask" user "Board Geometry/Soldermask Top")
		(3 "B.Mask" user "Board Geometry/Soldermask Bottom")
		(17 "Dwgs.User" user "User.Drawings")
		(19 "Cmts.User" user "User.Comments")
		(21 "Eco1.User" user "User.Eco1")
		(23 "Eco2.User" user "User.Eco2")
		(25 "Edge.Cuts" user "Board Geometry/Outline")
		(27 "Margin" user)
		(31 "F.CrtYd" user "Package Geometry/Place Bound Top")
		(29 "B.CrtYd" user "Package Geometry/Place Bound Bottom")
		(35 "F.Fab" user "Ref Des/Assembly Top")
		(33 "B.Fab" user "Ref Des/Assembly Bottom")
	)
	(footprint ""
		(layer "F.Cu")
		(at 83.428332 -331.97419 180)
		(property "Reference" "PC201"
			(at 0 0 180)
			(layer "F.SilkS")
			(hide yes)
			(effects
				(font
					(size 1.27 1.27)
				)
			)
		)
		(property "Value" ""
			(at 0 0 180)
			(layer "F.Fab")
			(effects
				(font
					(size 1.27 1.27)
				)
			)
		)
		(duplicate_pad_numbers_are_jumpers no)
		(fp_line
			(start 0.7874 0.4064)
			(end -0.7874 0.4064)
			(stroke
				(width 0.1524)
				(type default)
			)
			(layer "F.SilkS")
		)
		(fp_line
			(start 0.7874 -0.4064)
			(end 0.7874 0.4064)
			(stroke
				(width 0.1524)
				(type default)
			)
			(layer "F.SilkS")
		)
		(fp_line
			(start -0.7874 0.4064)
			(end -0.7874 -0.4064)
			(stroke
				(width 0.1524)
				(type default)
			)
			(layer "F.SilkS")
		)
		(fp_line
			(start -0.7874 -0.4064)
			(end 0.7874 -0.4064)
			(stroke
				(width 0.1524)
				(type default)
			)
			(layer "F.SilkS")
		)
		(fp_line
			(start 0.67945 0.3048)
			(end 0.120396 0.3048)
			(stroke
				(width 0.1)
				(type default)
			)
			(layer "F.Fab")
		)
		(fp_line
			(start 0.67945 -0.3048)
			(end 0.67945 0.3048)
			(stroke
				(width 0.1)
				(type default)
			)
			(layer "F.Fab")
		)
		(fp_line
			(start 0.12065 -0.2794)
			(end 0.12065 -0.3048)
			(stroke
				(width 0.1)
				(type default)
			)
			(layer "F.Fab")
		)
		(fp_line
			(start 0.12065 -0.3048)
			(end 0.67945 -0.3048)
			(stroke
				(width 0.1)
				(type default)
			)
			(layer "F.Fab")
		)
		(fp_line
			(start 0.120396 0.3048)
			(end 0.120396 0.2794)
			(stroke
				(width 0.1)
				(type default)
			)
			(layer "F.Fab")
		)
		(fp_line
			(start 0.120396 0.2794)
			(end -0.12065 0.2794)
			(stroke
				(width 0.1)
				(type default)
			)
			(layer "F.Fab")
		)
		(fp_line
			(start -0.12065 0.3048)
			(end -0.67945 0.3048)
			(stroke
				(width 0.1)
				(type default)
			)
			(layer "F.Fab")
		)
		(fp_line
			(start -0.12065 0.2794)
			(end -0.12065 0.3048)
			(stroke
				(width 0.1)
				(type default)
			)
			(layer "F.Fab")
		)
		(fp_line
			(start -0.12065 -0.2794)
			(end 0.12065 -0.2794)
			(stroke
				(width 0.1)
				(type default)
			)
			(layer "F.Fab")
		)
		(fp_line
			(start -0.12065 -0.305054)
			(end -0.12065 -0.2794)
			(stroke
				(width 0.1)
				(type default)
			)
			(layer "F.Fab")
		)
		(fp_line
			(start -0.67945 0.3048)
			(end -0.67945 -0.305054)
			(stroke
				(width 0.1)
				(type default)
			)
			(layer "F.Fab")
		)
		(fp_line
			(start -0.67945 -0.305054)
			(end -0.12065 -0.305054)
			(stroke
				(width 0.1)
				(type default)
			)
			(layer "F.Fab")
		)
		(pad "1" smd circle
			(at -0.40005 0 180)
			(size 0 0)
			(layers "F.Cu" "F.Mask" "F.Paste")
			(net "SW_PVDDCR_CPU1_P1_SW1")
		)
		(pad "2" smd circle
			(at 0.40005 0 180)
			(size 0 0)
			(layers "F.Cu" "F.Mask" "F.Paste")
			(net "SW_PVDDCR_CPU1_P1_SW1_RC")
		)
	)
	(footprint ""
		(layer "F.Cu")
		(at 22.479 -359.918 180)
		(property "Reference" "C310"
			(at 0 0 180)
			(layer "F.SilkS")
			(hide yes)
			(effects
				(font
					(size 1.27 1.27)
				)
			)
		)
		(property "Value" ""
			(at 0 0 180)
			(layer "F.Fab")
			(effects
				(font
					(size 1.27 1.27)
				)
			)
		)
		(duplicate_pad_numbers_are_jumpers no)
		(fp_line
			(start 0.7874 0.4064)
			(end -0.7874 0.4064)
			(stroke
				(width 0.1524)
				(type default)
			)
			(layer "F.SilkS")
		)
		(fp_line
			(start 0.7874 -0.4064)
			(end 0.7874 0.4064)
			(stroke
				(width 0.1524)
				(type default)
			)
			(layer "F.SilkS")
		)
		(fp_line
			(start -0.7874 0.4064)
			(end -0.7874 -0.4064)
			(stroke
				(width 0.1524)
				(type default)
			)
			(layer "F.SilkS")
		)
		(fp_line
			(start -0.7874 -0.4064)
			(end 0.7874 -0.4064)
			(stroke
				(width 0.1524)
				(type default)
			)
			(layer "F.SilkS")
		)
		(fp_line
			(start 0.67945 0.3048)
			(end 0.120396 0.3048)
			(stroke
				(width 0.1)
				(type default)
			)
			(layer "F.Fab")
		)
		(fp_line
			(start 0.67945 -0.3048)
			(end 0.67945 0.3048)
			(stroke
				(width 0.1)
				(type default)
			)
			(layer "F.Fab")
		)
		(fp_line
			(start 0.12065 -0.2794)
			(end 0.12065 -0.3048)
			(stroke
				(width 0.1)
				(type default)
			)
			(layer "F.Fab")
		)
		(fp_line
			(start 0.12065 -0.3048)
			(end 0.67945 -0.3048)
			(stroke
				(width 0.1)
				(type default)
			)
			(layer "F.Fab")
		)
		(fp_line
			(start 0.120396 0.3048)
			(end 0.120396 0.2794)
			(stroke
				(width 0.1)
				(type default)
			)
			(layer "F.Fab")
		)
		(fp_line
			(start 0.120396 0.2794)
			(end -0.12065 0.2794)
			(stroke
				(width 0.1)
				(type default)
			)
			(layer "F.Fab")
		)
		(fp_line
			(start -0.12065 0.3048)
			(end -0.67945 0.3048)
			(stroke
				(width 0.1)
				(type default)
			)
			(layer "F.Fab")
		)
		(fp_line
			(start -0.12065 0.2794)
			(end -0.12065 0.3048)
			(stroke
				(width 0.1)
				(type default)
			)
			(layer "F.Fab")
		)
		(fp_line
			(start -0.12065 -0.2794)
			(end 0.12065 -0.2794)
			(stroke
				(width 0.1)
				(type default)
			)
			(layer "F.Fab")
		)
		(fp_line
			(start -0.12065 -0.305054)
			(end -0.12065 -0.2794)
			(stroke
				(width 0.1)
				(type default)
			)
			(layer "F.Fab")
		)
		(fp_line
			(start -0.67945 0.3048)
			(end -0.67945 -0.305054)
			(stroke
				(width 0.1)
				(type default)
			)
			(layer "F.Fab")
		)
		(fp_line
			(start -0.67945 -0.305054)
			(end -0.12065 -0.305054)
			(stroke
				(width 0.1)
				(type default)
			)
			(layer "F.Fab")
		)
		(pad "1" smd circle
			(at -0.40005 0 180)
			(size 0 0)
			(layers "F.Cu" "F.Mask" "F.Paste")
			(net "SVID_PVDDCR_CPU1_P1_SVC_R")
		)
		(pad "2" smd circle
			(at 0.40005 0 180)
			(size 0 0)
			(layers "F.Cu" "F.Mask" "F.Paste")
			(net "GND")
		)
	)
)
